# S9S_MB_2U (Grand Teton) — schematic parts with pin connectivity, parts 1612–1612 of 6093; source: Cadence DE-HDL packaged netlist (pstxprt.dat, pstxnet.dat, pstchip.dat)

J19  SCONN288_ADR50017P130CC  SCONN288_ADR50017-P130CC IO  pkg DDR288S_1-1VXB  page 100
  1  VIN_BULK0  POWER  = P12V_S3_AUX_CPU1_NVDIMM
  2  RFU0  TRI  = TP_CHB_CPU1_DIMM1_FRU_0
  3  VIN_MGMT  POWER  = P3V3_AUX
  4  HSCL  IN  = I3C_SPD_DDRABCD_CPU1_LVC1_SCL_2
  5  HSDA  BI  = I3C_SPD_DDRABCD_CPU1_LVC1_SDA
  6  VSS0  POWER  = GND
  7  DQ0_A  BI  = M_B_CPU1_SA_DQ<0>
  8  VSS1  POWER  = GND
  9  DQ1_A  BI  = M_B_CPU1_SA_DQ<1>
  10  VSS2  POWER  = GND
  11  DQS0_A_T  BI  = M_B_CPU1_SA_DQS_DP<0>
  12  DQS0_A_C  BI  = M_B_CPU1_SA_DQS_DN<0>
  13  VSS3  POWER  = GND
  14  DQ4_A  BI  = M_B_CPU1_SA_DQ<4>
  15  VSS4  POWER  = GND
  16  DQ5_A  BI  = M_B_CPU1_SA_DQ<5>
  17  VSS5  POWER  = GND
  18  DQ8_A  BI  = M_B_CPU1_SA_DQ<8>
  19  VSS6  POWER  = GND
  20  DQ9_A  BI  = M_B_CPU1_SA_DQ<9>
  21  VSS7  POWER  = GND
  22  DQS1_A_T  BI  = M_B_CPU1_SA_DQS_DP<1>
  23  DQS1_A_C  BI  = M_B_CPU1_SA_DQS_DN<1>
  24  VSS8  POWER  = GND
  25  DQ12_A  BI  = M_B_CPU1_SA_DQ<12>
  26  VSS9  POWER  = GND
  27  DQ13_A  BI  = M_B_CPU1_SA_DQ<13>
  28  VSS10  POWER  = GND
  29  DQ16_A  BI  = M_B_CPU1_SA_DQ<16>
  30  VSS11  POWER  = GND
  31  DQ17_A  BI  = M_B_CPU1_SA_DQ<17>
  32  VSS12  POWER  = GND
  33  DQS2_A_T  BI  = M_B_CPU1_SA_DQS_DP<2>
  34  DQS2_A_C  BI  = M_B_CPU1_SA_DQS_DN<2>
  35  VSS13  POWER  = GND
  36  DQ20_A  BI  = M_B_CPU1_SA_DQ<20>
  37  VSS14  POWER  = GND
  38  DQ21_A  BI  = M_B_CPU1_SA_DQ<21>
  39  VSS15  POWER  = GND
  40  DQ24_A  BI  = M_B_CPU1_SA_DQ<24>
  41  VSS16  POWER  = GND
  42  DQ25_A  BI  = M_B_CPU1_SA_DQ<25>
  43  VSS17  POWER  = GND
  44  DQS3_A_T  BI  = M_B_CPU1_SA_DQS_DP<3>
  45  DQS3_A_C  BI  = M_B_CPU1_SA_DQS_DN<3>
  46  VSS18  POWER  = GND
  47  DQ28_A  BI  = M_B_CPU1_SA_DQ<28>
  48  VSS19  POWER  = GND
  49  DQ29_A  BI  = M_B_CPU1_SA_DQ<29>
  50  VSS20  POWER  = GND
  51  CB0_A  BI  = M_B_CPU1_SA_CB<0>
  52  VSS21  POWER  = GND
  53  CB1_A  BI  = M_B_CPU1_SA_CB<1>
  54  VSS22  POWER  = GND
  55  DQS4_A_T  BI  = M_B_CPU1_SA_DQS_DP<4>
  56  DQS4_A_C  BI  = M_B_CPU1_SA_DQS_DN<4>
  57  VSS23  POWER  = GND
  58  CB4_A  BI  = M_B_CPU1_SA_CB<4>
  59  VSS24  POWER  = GND
  60  CB5_A  BI  = M_B_CPU1_SA_CB<5>
  61  VSS25  POWER  = GND
  62  ALERT_N  OUT  = M_B_CPU1_ALERT_N
  63  VSS26  POWER  = GND
  64  CS0_A_N  IN  = M_B_CPU1_SA_CS_N<0>
  65  VSS27  POWER  = GND
  66  CA0_A  IN  = M_B_CPU1_SA_CA<0>
  67  VSS28  POWER  = GND
  68  CA2_A  IN  = M_B_CPU1_SA_CA<2>
  69  VSS29  POWER  = GND
  70  CA4_A  IN  = M_B_CPU1_SA_CA<4>
  71  VSS30  POWER  = GND
  72  CA6_A  IN  = M_B_CPU1_SA_CA<6>
  73  VSS31  POWER  = GND
  74  PAR_A  IN  = M_B_CPU1_SA_PAR
  75  VSS32  POWER  = GND
  76  CA0_B  IN  = M_B_CPU1_SB_CA<0>
  77  VSS33  POWER  = GND
  78  CA2_B  IN  = M_B_CPU1_SB_CA<2>
  79  VSS34  POWER  = GND
  80  CA4_B  IN  = M_B_CPU1_SB_CA<4>
  81  VSS35  POWER  = GND
  82  CA6_B  IN  = M_B_CPU1_SB_CA<6>
  83  VSS36  POWER  = GND
  84  CS0_B_N  IN  = M_B_CPU1_SB_CS_N<0>
  85  VSS37  POWER  = GND
  86  \lbd||rsp_a_n\  OUT  = M_B_CPU1_SA_RSP<0>
  87  \lbs||rsp_b_n\  OUT  = M_B_CPU1_SB_RSP<0>
  88  VSS38  POWER  = GND
  89  CB4_B  BI  = M_B_CPU1_SB_CB<4>
  90  VSS39  POWER  = GND
  91  CB5_B  BI  = M_B_CPU1_SB_CB<5>
  92  VSS40  POWER  = GND
  93  \dqs9_b_t||tdqs9_b_t||dbi4_b_n\  BI  = M_B_CPU1_SB_DQS_DP<9>
  94  \dqs9_b_c||tdqs9_b_c\  BI  = M_B_CPU1_SB_DQS_DN<9>
  95  VSS41  POWER  = GND
  96  CB0_B  BI  = M_B_CPU1_SB_CB<0>
  97  VSS42  POWER  = GND
  98  CB1_B  BI  = M_B_CPU1_SB_CB<1>
  99  VSS43  POWER  = GND
  100  DQ0_B  BI  = M_B_CPU1_SB_DQ<0>
  101  VSS44  POWER  = GND
  102  DQ1_B  BI  = M_B_CPU1_SB_DQ<1>
  103  VSS45  POWER  = GND
  104  DQS0_B_T  BI  = M_B_CPU1_SB_DQS_DP<0>
  105  DQS0_B_C  BI  = M_B_CPU1_SB_DQS_DN<0>
  106  VSS46  POWER  = GND
  107  DQ4_B  BI  = M_B_CPU1_SB_DQ<4>
  108  VSS47  POWER  = GND
  109  DQ5_B  BI  = M_B_CPU1_SB_DQ<5>
  110  VSS48  POWER  = GND
  111  DQ8_B  BI  = M_B_CPU1_SB_DQ<8>
  112  VSS49  POWER  = GND
  113  DQ9_B  BI  = M_B_CPU1_SB_DQ<9>
  114  VSS50  POWER  = GND
  115  DQS1_B_T  BI  = M_B_CPU1_SB_DQS_DP<1>
  116  DQS1_B_C  BI  = M_B_CPU1_SB_DQS_DN<1>
  117  VSS51  POWER  = GND
  118  DQ12_B  BI  = M_B_CPU1_SB_DQ<12>
  119  VSS52  POWER  = GND
  120  DQ13_B  BI  = M_B_CPU1_SB_DQ<13>
  121  VSS53  POWER  = GND
  122  DQ16_B  BI  = M_B_CPU1_SB_DQ<16>
  123  VSS54  POWER  = GND
  124  DQ17_B  BI  = M_B_CPU1_SB_DQ<17>
  125  VSS55  POWER  = GND
  126  DQS2_B_T  BI  = M_B_CPU1_SB_DQS_DP<2>
  127  DQS2_B_C  BI  = M_B_CPU1_SB_DQS_DN<2>
  128  VSS56  POWER  = GND
  129  DQ20_B  BI  = M_B_CPU1_SB_DQ<20>
  130  VSS57  POWER  = GND
  131  DQ21_B  BI  = M_B_CPU1_SB_DQ<21>
  132  VSS58  POWER  = GND
  133  DQ24_B  BI  = M_B_CPU1_SB_DQ<24>
  134  VSS59  POWER  = GND
  135  DQ25_B  BI  = M_B_CPU1_SB_DQ<25>
  136  VSS60  POWER  = GND
  137  DQS3_B_T  BI  = M_B_CPU1_SB_DQS_DP<3>
  138  DQS3_B_C  BI  = M_B_CPU1_SB_DQS_DN<3>
  139  VSS61  POWER  = GND
  140  DQ28_B  BI  = M_B_CPU1_SB_DQ<28>
  141  VSS62  POWER  = GND
  142  DQ29_B  BI  = M_B_CPU1_SB_DQ<29>
  143  VSS63  POWER  = GND
  144  RFU1  TRI  = TP_CHB_CPU1_DIMM1_FRU_1
  145  VIN_BULK1  POWER  = P12V_S3_AUX_CPU1_NVDIMM
  146  VIN_BULK2  POWER  = P12V_S3_AUX_CPU1_NVDIMM
  147  \pwr_good||fail_n\  BI  = PWRGD_CHB_CPU1_DIMM1
  148  HSA  IN  = PD_CHB_CPU1_DIMM1_SAA
  149  RFU2  TRI  = TP_CHB_CPU1_DIMM1_FRU_2
  150  RFU3  TRI  = TP_CHB_CPU1_DIMM1_FRU_3
  151  VSS64  POWER  = GND
  152  DQ2_A  BI  = M_B_CPU1_SA_DQ<2>
  153  VSS65  POWER  = GND
  154  DQ3_A  BI  = M_B_CPU1_SA_DQ<3>
  155  VSS66  POWER  = GND
  156  \dqs5_a_c||tdqs5_a_c||dqs5_a_t||tdqs5_a_t\  BI  = M_B_CPU1_SA_DQS_DN<5>
  157  \dqs5_a_t||tdqs5_a_t\  BI  = M_B_CPU1_SA_DQS_DP<5>
  158  VSS67  POWER  = GND
  159  DQ6_A  BI  = M_B_CPU1_SA_DQ<6>
  160  VSS68  POWER  = GND
  161  DQ7_A  BI  = M_B_CPU1_SA_DQ<7>
  162  VSS69  POWER  = GND
  163  DQ10_A  BI  = M_B_CPU1_SA_DQ<10>
  164  VSS70  POWER  = GND
  165  DQ11_A  BI  = M_B_CPU1_SA_DQ<11>
  166  VSS71  POWER  = GND
  167  \dqs6_a_c||tdqs6_a_c||dqs6_a_t||tdqs6_a_t\  BI  = M_B_CPU1_SA_DQS_DN<6>
  168  \dqs6_a_t||tdqs6_a_t\  BI  = M_B_CPU1_SA_DQS_DP<6>
  169  VSS72  POWER  = GND
  170  DQ14_A  BI  = M_B_CPU1_SA_DQ<14>
  171  VSS73  POWER  = GND
  172  DQ15_A  BI  = M_B_CPU1_SA_DQ<15>
  173  VSS74  POWER  = GND
  174  DQ18_A  BI  = M_B_CPU1_SA_DQ<18>
  175  VSS75  POWER  = GND
  176  DQ19_A  BI  = M_B_CPU1_SA_DQ<19>
  177  VSS76  POWER  = GND
  178  \dqs7_a_c||tdqs7_a_c\  BI  = M_B_CPU1_SA_DQS_DN<7>
  179  \dqs7_a_t||tdqs7_a_t\  BI  = M_B_CPU1_SA_DQS_DP<7>
  180  VSS77  POWER  = GND
  181  DQ22_A  BI  = M_B_CPU1_SA_DQ<22>
  182  VSS78  POWER  = GND
  183  DQ23_A  BI  = M_B_CPU1_SA_DQ<23>
  184  VSS79  POWER  = GND
  185  DQ26_A  BI  = M_B_CPU1_SA_DQ<26>
  186  VSS80  POWER  = GND
  187  DQ27_A  BI  = M_B_CPU1_SA_DQ<27>
  188  VSS81  POWER  = GND
  189  \dqs8_a_c||tdqs8_a_c\  BI  = M_B_CPU1_SA_DQS_DN<8>
  190  \dqs8_a_t||tdqs8_a_t\  BI  = M_B_CPU1_SA_DQS_DP<8>
  191  VSS82  POWER  = GND
  192  DQ30_A  BI  = M_B_CPU1_SA_DQ<30>
  193  VSS83  POWER  = GND
  194  DQ31_A  BI  = M_B_CPU1_SA_DQ<31>
  195  VSS84  POWER  = GND
  196  CB2_A  BI  = M_B_CPU1_SA_CB<2>
  197  VSS85  POWER  = GND
  198  CB3_A  BI  = M_B_CPU1_SA_CB<3>
  199  VSS86  POWER  = GND
  200  \dqs9_a_c||tdqs9_a_c\  BI  = M_B_CPU1_SA_DQS_DN<9>
  201  \dqs9_a_t||tdqs9_a_t\  BI  = M_B_CPU1_SA_DQS_DP<9>
  202  VSS87  POWER  = GND
  203  CB6_A  BI  = M_B_CPU1_SA_CB<6>
  204  VSS88  POWER  = GND
  205  CB7_A  BI  = M_B_CPU1_SA_CB<7>
  206  VSS89  POWER  = GND
  207  RESET_N  IN  = RST_M_AB_CPU1_FPGA_N
  208  VSS90  POWER  = GND
  209  CS1_A_N  IN  = M_B_CPU1_SA_CS_N<1>
  210  VSS91  POWER  = GND
  211  CA1_A  IN  = M_B_CPU1_SA_CA<1>
  212  VSS92  POWER  = GND
  213  CA3_A  IN  = M_B_CPU1_SA_CA<3>
  214  VSS93  POWER  = GND
  215  CA5_A  IN  = M_B_CPU1_SA_CA<5>
  216  VSS94  POWER  = GND
  217  CK_T  IN  = M_B_CPU1_CLK_DP<0>
  218  CK_C  IN  = M_B_CPU1_CLK_DN<0>
  219  VSS95  POWER  = GND
  220  RFU4  TRI  = TP_CHB_CPU1_DIMM1_FRU_4
  221  CA1_B  IN  = M_B_CPU1_SB_CA<1>
  222  VSS96  POWER  = GND
  223  CA3_B  IN  = M_B_CPU1_SB_CA<3>
  224  VSS97  POWER  = GND
  225  CA5_B  IN  = M_B_CPU1_SB_CA<5>
  226  VSS98  POWER  = GND
  227  PAR_B  IN  = M_B_CPU1_SB_PAR
  228  VSS99  POWER  = GND
  229  CS1_B_N  IN  = M_B_CPU1_SB_CS_N<1>
  230  VSS100  POWER  = GND
  231  RFU5  TRI  = TP_CHB_CPU1_DIMM1_FRU_5
  232  RFU6  TRI  = TP_CHB_CPU1_DIMM1_FRU_6
  233  VSS101  POWER  = GND
  234  CB6_B  BI  = M_B_CPU1_SB_CB<6>
  235  VSS102  POWER  = GND
  236  CB7_B  BI  = M_B_CPU1_SB_CB<7>
  237  VSS103  POWER  = GND
  238  DQS4_B_C  BI  = M_B_CPU1_SB_DQS_DN<4>
  239  DQS4_B_T  BI  = M_B_CPU1_SB_DQS_DP<4>
  240  VSS104  POWER  = GND
  241  CB2_B  BI  = M_B_CPU1_SB_CB<2>
  242  VSS105  POWER  = GND
  243  CB3_B  BI  = M_B_CPU1_SB_CB<3>
  244  VSS106  POWER  = GND
  245  DQ2_B  BI  = M_B_CPU1_SB_DQ<2>
  246  VSS107  POWER  = GND
  247  DQ3_B  BI  = M_B_CPU1_SB_DQ<3>
  248  VSS108  POWER  = GND
  249  \dqs5_b_c||tdqs5_b_c\  BI  = M_B_CPU1_SB_DQS_DN<5>
  250  \dqs5_b_t||tdqs5_b_t\  BI  = M_B_CPU1_SB_DQS_DP<5>
  251  VSS109  POWER  = GND
  252  DQ6_B  BI  = M_B_CPU1_SB_DQ<6>
  253  VSS110  POWER  = GND
  254  DQ7_B  BI  = M_B_CPU1_SB_DQ<7>
  255  VSS111  POWER  = GND
  256  DQ10_B  BI  = M_B_CPU1_SB_DQ<10>
  257  VSS112  POWER  = GND
  258  DQ11_B  BI  = M_B_CPU1_SB_DQ<11>
  259  VSS113  POWER  = GND
  260  \dqs6_b_c||tdqs6_b_c\  BI  = M_B_CPU1_SB_DQS_DN<6>
  261  \dqs6_b_t||tdqs6_b_t\  BI  = M_B_CPU1_SB_DQS_DP<6>
  262  VSS114  POWER  = GND
  263  DQ14_B  BI  = M_B_CPU1_SB_DQ<14>
  264  VSS115  POWER  = GND
  265  DQ15_B  BI  = M_B_CPU1_SB_DQ<15>
  266  VSS116  POWER  = GND
  267  DQ18_B  BI  = M_B_CPU1_SB_DQ<18>
  268  VSS117  POWER  = GND
  269  DQ19_B  BI  = M_B_CPU1_SB_DQ<19>
  270  VSS118  POWER  = GND
  271  \dqs7_b_c||tdqs7_b_c\  BI  = M_B_CPU1_SB_DQS_DN<7>
  272  \dqs7_b_t||tdqs7_b_t\  BI  = M_B_CPU1_SB_DQS_DP<7>
  273  VSS119  POWER  = GND
  274  DQ22_B  BI  = M_B_CPU1_SB_DQ<22>
  275  VSS120  POWER  = GND
  276  DQ23_B  BI  = M_B_CPU1_SB_DQ<23>
  277  VSS121  POWER  = GND
  278  DQ26_B  BI  = M_B_CPU1_SB_DQ<26>
  279  VSS122  POWER  = GND
  280  DQ27_B  BI  = M_B_CPU1_SB_DQ<27>
  281  VSS123  POWER  = GND
  282  \dqs8_b_c||tdqs8_b_c\  BI  = M_B_CPU1_SB_DQS_DN<8>
  283  \dqs8_b_t||tdqs8_b_t\  BI  = M_B_CPU1_SB_DQS_DP<8>
  284  VSS124  POWER  = GND
  285  DQ30_B  BI  = M_B_CPU1_SB_DQ<30>
  286  VSS125  POWER  = GND
  287  DQ31_B  BI  = M_B_CPU1_SB_DQ<31>
  288  VSS126  POWER  = GND
  G1  G1  POWER  = GND
  G2  G2  POWER  = GND
  G3  G3  POWER  = GND
